FILE_TYPE = CONNECTIVITY;
{Allegro Design Entry HDL 17.4-2019 S026 (4007227) 1/17/2022}
"PAGE_NUMBER" = 61;
0"NC";
END.
